# BASEBOARD_FAB2 (Tioga Pass) — schematic netlist excerpt (pin names and nets, part order shuffled) for the footprints in the layout excerpt that follows; sources: Cadence DE-HDL packaged netlist, KiCad conversion of Wiwynn_Tioga_Pass_MB.brd

J8G1  SCONN200_H68296001  CONN  pkg SM  page 108
  IO1  = P12V
  IO2  = P12V
  IO3  = P12V
  IO4  = P12V
  IO5  = P12V
  IO6  = P12V
  IO7  = P12V
  IO8  = P12V
  IO9  = P12V
  IO10  = P12V
  IO11  = P12V
  IO12  = P12V
  IO13  = GND
  IO14  = GND
  IO15  = SMB_SLOTX24_STBY_LVC3_SDA_R2
  IO16  = IRQ_OOB_MGMT_RISER_ALERT_N
  IO17  = SMB_SLOTX24_STBY_LVC3_SCL_R2
  IO18  = FM_SLT_CFG1
  IO19  = FM_SLT_CFG0
  IO20  = FM_PWRBRK_SLOT_N
  IO21  = P3V3
  IO22  = P3V3
  IO23  = P3V3
  IO24  = P3V3
  IO25  = P3V3_STBY
  IO26  = GND
  IO27  = PU_PCH_TLS_ENABLE_STRAP
  IO28  = FM_PE_SLOTX24_WAKE_N
  IO29  = RST_PCIE_RISER1_PERST_R_N
  IO30  = SMB_HOST_STBY_LVC3_SDA_R5
  IO31  = GND
  IO32  = SMB_HOST_STBY_LVC3_SCL_R5
  IO33  = CLK_100M_PCH_SLOTX24_S5_DP
  IO34  = GND
  IO35  = CLK_100M_PCH_SLOTX24_S5_DN
  IO36  = CLK_100M_PCH_SLOTX24_S4_DP
  IO37  = GND
  IO38  = CLK_100M_PCH_SLOTX24_S4_DN
  IO39  = CLK_100M_PCH_SLOTX24_S0_DP
  IO40  = GND
  IO41  = CLK_100M_PCH_SLOTX24_S0_DN
  IO42  = CLK_100M_PCH_SLOTX24_S1_DP
  IO43  = GND
  IO44  = CLK_100M_PCH_SLOTX24_S1_DN
  IO45  = CLK_100M_PCH_SLOTX24_S3_DP
  IO46  = GND
  IO47  = CLK_100M_PCH_SLOTX24_S3_DN
  IO48  = CLK_100M_PCH_SLOTX24_S2_DP
  IO49  = GND
  IO50  = CLK_100M_PCH_SLOTX24_S2_DN
  IO51  = P3E_CPU0_PE1_PCH_CON_TXN<15>
  IO52  = GND
  IO53  = P3E_CPU0_PE1_PCH_CON_TXP<15>
  IO54  = P3E_CPU0_PE1_PCH_CON_RXN<15>
  IO55  = GND
  IO56  = P3E_CPU0_PE1_PCH_CON_RXP<15>
  IO57  = P3E_CPU0_PE1_PCH_CON_TXP<14>
  IO58  = GND
  IO59  = P3E_CPU0_PE1_PCH_CON_TXN<14>
  IO60  = P3E_CPU0_PE1_PCH_CON_RXN<14>
  IO61  = GND
  IO62  = P3E_CPU0_PE1_PCH_CON_RXP<14>
  IO63  = TP_SLOTX24_RSVD63
  IO64  = GND
  IO65  = GND
  IO66  = TP_SLOTX24_RSVD66
  IO67  = P3E_CPU0_PE1_PCH_CON_TXN<13>
  IO68  = GND
  IO69  = P3E_CPU0_PE1_PCH_CON_TXP<13>
  IO70  = P3E_CPU0_PE1_PCH_CON_RXN<13>
  IO71  = GND
  IO72  = P3E_CPU0_PE1_PCH_CON_RXP<13>
  IO73  = P3E_CPU0_PE1_PCH_CON_TXN<12>
  IO74  = GND
  IO75  = P3E_CPU0_PE1_PCH_CON_TXP<12>
  IO76  = P3E_CPU0_PE1_PCH_CON_RXN<12>
  IO77  = GND
  IO78  = P3E_CPU0_PE1_PCH_CON_RXP<12>
  IO79  = P3E_CPU0_PE1_PCH_CON_TXN<11>
  IO80  = GND
  IO81  = P3E_CPU0_PE1_PCH_CON_TXP<11>
  IO82  = P3E_CPU0_PE1_PCH_CON_RXN<11>
  IO83  = GND
  IO84  = P3E_CPU0_PE1_PCH_CON_RXP<11>
  IO85  = P3E_CPU0_PE1_PCH_CON_TXN<10>
  IO86  = GND
  IO87  = P3E_CPU0_PE1_PCH_CON_TXP<10>
  IO88  = P3E_CPU0_PE1_PCH_CON_RXN<10>
  IO89  = GND
  IO90  = P3E_CPU0_PE1_PCH_CON_RXP<10>
  IO91  = P3E_CPU0_PE1_PCH_CON_TXN<9>
  IO92  = GND
  IO93  = P3E_CPU0_PE1_PCH_CON_TXP<9>
  IO94  = P3E_CPU0_PE1_PCH_CON_RXN<9>
  IO95  = GND
  IO96  = P3E_CPU0_PE1_PCH_CON_RXP<9>
  IO97  = P3E_CPU0_PE1_PCH_CON_TXN<8>
  IO98  = GND
  IO99  = P3E_CPU0_PE1_PCH_CON_TXP<8>
  IO100  = P3E_CPU0_PE1_PCH_CON_RXN<8>
  IO101  = GND
  IO102  = P3E_CPU0_PE1_PCH_CON_RXP<8>
  IO103  = P3E_CPU0_PE1_SS_C_TXP<7>
  IO104  = GND
  IO105  = P3E_CPU0_PE1_SS_C_TXN<7>
  IO106  = P3E_CPU0_PE1_SS_R_RXN<7>
  IO107  = GND
  IO108  = P3E_CPU0_PE1_SS_R_RXP<7>
  IO109  = P3E_CPU0_PE1_SS_C_TXN<6>
  IO110  = GND
  IO111  = P3E_CPU0_PE1_SS_C_TXP<6>
  IO112  = P3E_CPU0_PE1_SS_R_RXN<6>
  IO113  = GND
  IO114  = P3E_CPU0_PE1_SS_R_RXP<6>
  IO115  = P3E_CPU0_PE1_SS_C_TXN<5>
  IO116  = GND
  IO117  = P3E_CPU0_PE1_SS_C_TXP<5>
  IO118  = P3E_CPU0_PE1_SS_R_RXN<5>
  IO119  = GND
  IO120  = P3E_CPU0_PE1_SS_R_RXP<5>
  IO121  = P3E_CPU0_PE1_SS_C_TXN<4>
  IO122  = GND
  IO123  = P3E_CPU0_PE1_SS_C_TXP<4>
  IO124  = P3E_CPU0_PE1_SS_R_RXN<4>
  IO125  = GND
  IO126  = P3E_CPU0_PE1_SS_R_RXP<4>
  IO127  = P3E_CPU0_PE1_SS_C_TXN<3>
  IO128  = GND
  IO129  = P3E_CPU0_PE1_SS_C_TXP<3>
  IO130  = P3E_CPU0_PE1_SS_R_RXN<3>
  IO131  = GND
  IO132  = P3E_CPU0_PE1_SS_R_RXP<3>
  IO133  = P3E_CPU0_PE1_SS_C_TXN<2>
  IO134  = GND
  IO135  = P3E_CPU0_PE1_SS_C_TXP<2>
  IO136  = P3E_CPU0_PE1_SS_R_RXN<2>
  IO137  = GND
  IO138  = P3E_CPU0_PE1_SS_R_RXP<2>
  IO139  = P3E_CPU0_PE1_SS_C_TXN<1>
  IO140  = GND
  IO141  = P3E_CPU0_PE1_SS_C_TXP<1>
  IO142  = P3E_CPU0_PE1_SS_R_RXN<1>
  IO143  = GND
  IO144  = P3E_CPU0_PE1_SS_R_RXP<1>
  IO145  = P3E_CPU0_PE1_SS_C_TXN<0>
  IO146  = GND
  IO147  = P3E_CPU0_PE1_SS_C_TXP<0>
  IO148  = P3E_CPU0_PE1_SS_R_RXN<0>
  IO149  = GND
  IO150  = P3E_CPU0_PE1_SS_R_RXP<0>
  IO151  = P3E_CPU0_PE2_SS_C_TXN<0>
  IO152  = GND
  IO153  = P3E_CPU0_PE2_SS_C_TXP<0>
  IO154  = P3E_CPU0_PE2_SS_RXN<0>
  IO155  = GND
  IO156  = P3E_CPU0_PE2_SS_RXP<0>
  IO157  = P3E_CPU0_PE2_SS_C_TXP<1>
  IO158  = GND
  IO159  = P3E_CPU0_PE2_SS_C_TXN<1>
  IO160  = P3E_CPU0_PE2_SS_RXN<1>
  IO161  = GND
  IO162  = P3E_CPU0_PE2_SS_RXP<1>
  IO163  = P3E_CPU0_PE2_SS_C_TXN<2>
  IO164  = GND
  IO165  = P3E_CPU0_PE2_SS_C_TXP<2>
  IO166  = P3E_CPU0_PE2_SS_RXN<2>
  IO167  = GND
  IO168  = P3E_CPU0_PE2_SS_RXP<2>
  IO169  = P3E_CPU0_PE2_SS_C_TXN<3>
  IO170  = GND
  IO171  = P3E_CPU0_PE2_SS_C_TXP<3>
  IO172  = P3E_CPU0_PE2_SS_RXN<3>
  IO173  = GND
  IO174  = P3E_CPU0_PE2_SS_RXP<3>
  IO175  = P3E_CPU0_PE2_SS_C_TXN<4>
  IO176  = GND
  IO177  = P3E_CPU0_PE2_SS_C_TXP<4>
  IO178  = P3E_CPU0_PE2_SS_RXN<4>
  IO179  = GND
  IO180  = P3E_CPU0_PE2_SS_RXP<4>
  IO181  = P3E_CPU0_PE2_SS_C_TXN<5>
  IO182  = GND
  IO183  = P3E_CPU0_PE2_SS_C_TXP<5>
  IO184  = P3E_CPU0_PE2_SS_RXN<5>
  IO185  = GND
  IO186  = P3E_CPU0_PE2_SS_RXP<5>
  IO187  = P3E_CPU0_PE2_SS_C_TXN<6>
  IO188  = GND
  IO189  = P3E_CPU0_PE2_SS_C_TXP<6>
  IO190  = P3E_CPU0_PE2_SS_RXP<6>
  IO191  = GND
  IO192  = P3E_CPU0_PE2_SS_RXN<6>
  IO193  = P3E_CPU0_PE2_SS_C_TXN<7>
  IO194  = GND
  IO195  = P3E_CPU0_PE2_SS_C_TXP<7>
  IO196  = P3E_CPU0_PE2_SS_RXN<7>
  IO197  = GND
  IO198  = P3E_CPU0_PE2_SS_RXP<7>
  IO199  = FM_PRSNT_2_6_N
  IO200  = GND
  MH1  = GND
  MH2  = GND

(kicad_pcb
	(version 20260206)
	(generator "pcbnew")
	(generator_version "10.0")
	(general
		(thickness 1.6)
		(legacy_teardrops no)
	)
	(paper "A4")
	(title_block
		(title "Wiwynn_Tioga_Pass_MB.brd")
		(comment 1 "Tioga Pass / footprint 949 of 4770 (J8G1), pads 186-204 of 204")
	)
	(layers
		(0 "F.Cu" signal "TOP")
		(4 "In1.Cu" signal "L2GND")
		(6 "In2.Cu" signal "L3")
		(8 "In3.Cu" signal "L4GND")
		(10 "In4.Cu" signal "L5")
		(12 "In5.Cu" signal "L6GND")
		(14 "In6.Cu" signal "L7VCC")
		(16 "In7.Cu" signal "L8VCC")
		(18 "In8.Cu" signal "L9GND")
		(20 "In9.Cu" signal "L10")
		(22 "In10.Cu" signal "L11GND")
		(24 "In11.Cu" signal "L12")
		(26 "In12.Cu" signal "L13GND")
		(2 "B.Cu" signal "BOTTOM")
		(9 "F.Adhes" user "F.Adhesive")
		(11 "B.Adhes" user "B.Adhesive")
		(13 "F.Paste" user "Package Geometry/Pastemask Top")
		(15 "B.Paste" user "Package Geometry/Pastemask Bottom")
		(5 "F.SilkS" user "Ref Des/Silkscreen Top")
		(7 "B.SilkS" user "Ref Des/Silkscreen Bottom")
		(1 "F.Mask" user "Board Geometry/Soldermask Top")
		(3 "B.Mask" user "Board Geometry/Soldermask Bottom")
		(17 "Dwgs.User" user "User.Drawings")
		(19 "Cmts.User" user "User.Comments")
		(21 "Eco1.User" user "User.Eco1")
		(23 "Eco2.User" user "User.Eco2")
		(25 "Edge.Cuts" user "Board Geometry/Outline")
		(27 "Margin" user)
		(31 "F.CrtYd" user "Package Geometry/Place Bound Top")
		(29 "B.CrtYd" user "Package Geometry/Place Bound Bottom")
		(35 "F.Fab" user "Ref Des/Assembly Top")
		(33 "B.Fab" user "Ref Des/Assembly Bottom")
	)
	(footprint ""
		(layer "F.Cu")
		(at 474.080078 -7.789672 -90)
		(property "Reference" "J8G1"
			(at -3.126486 25.39111 0)
			(unlocked yes)
			(layer "F.SilkS")
			(effects
				(font
					(size 0.7874 0.5842)
					(thickness 0.1524)
				)
				(justify left)
			)
		)
		(property "Value" ""
			(at 0 0 270)
			(layer "F.Fab")
			(effects
				(font
					(size 1.27 1.27)
				)
			)
		)
		(duplicate_pad_numbers_are_jumpers no)
		(pad "184" smd rect
			(at 3.4036 76.008992 270)
			(size 1.1938 0.508)
			(layers "F.Cu" "F.Mask" "F.Paste")
			(net "P3E_CPU0_PE2_SS_RXN<5>")
		)
		(pad "185" smd rect
			(at 0 76.809092 270)
			(size 1.1938 0.508)
			(layers "F.Cu" "F.Mask" "F.Paste")
			(net "GND")
		)
		(pad "186" smd rect
			(at 3.4036 76.809092 270)
			(size 1.1938 0.508)
			(layers "F.Cu" "F.Mask" "F.Paste")
			(net "P3E_CPU0_PE2_SS_RXP<5>")
		)
		(pad "187" smd rect
			(at 0 77.609192 270)
			(size 1.1938 0.508)
			(layers "F.Cu" "F.Mask" "F.Paste")
			(net "P3E_CPU0_PE2_SS_C_TXN<6>")
		)
		(pad "188" smd rect
			(at 3.4036 77.609192 270)
			(size 1.1938 0.508)
			(layers "F.Cu" "F.Mask" "F.Paste")
			(net "GND")
		)
		(pad "189" smd rect
			(at 0 78.409292 270)
			(size 1.1938 0.508)
			(layers "F.Cu" "F.Mask" "F.Paste")
			(net "P3E_CPU0_PE2_SS_C_TXP<6>")
		)
		(pad "190" smd rect
			(at 3.4036 78.409292 270)
			(size 1.1938 0.508)
			(layers "F.Cu" "F.Mask" "F.Paste")
			(net "P3E_CPU0_PE2_SS_RXP<6>")
		)
		(pad "191" smd rect
			(at 0 79.209392 270)
			(size 1.1938 0.508)
			(layers "F.Cu" "F.Mask" "F.Paste")
			(net "GND")
		)
		(pad "192" smd rect
			(at 3.4036 79.209392 270)
			(size 1.1938 0.508)
			(layers "F.Cu" "F.Mask" "F.Paste")
			(net "P3E_CPU0_PE2_SS_RXN<6>")
		)
		(pad "193" smd rect
			(at 0 80.009492 270)
			(size 1.1938 0.508)
			(layers "F.Cu" "F.Mask" "F.Paste")
			(net "P3E_CPU0_PE2_SS_C_TXN<7>")
		)
		(pad "194" smd rect
			(at 3.4036 80.009492 270)
			(size 1.1938 0.508)
			(layers "F.Cu" "F.Mask" "F.Paste")
			(net "GND")
		)
		(pad "195" smd rect
			(at 0 80.809592 270)
			(size 1.1938 0.508)
			(layers "F.Cu" "F.Mask" "F.Paste")
			(net "P3E_CPU0_PE2_SS_C_TXP<7>")
		)
		(pad "196" smd rect
			(at 3.4036 80.809592 270)
			(size 1.1938 0.508)
			(layers "F.Cu" "F.Mask" "F.Paste")
			(net "P3E_CPU0_PE2_SS_RXN<7>")
		)
		(pad "197" smd rect
			(at 0 81.609692 270)
			(size 1.1938 0.508)
			(layers "F.Cu" "F.Mask" "F.Paste")
			(net "GND")
		)
		(pad "198" smd rect
			(at 3.4036 81.609692 270)
			(size 1.1938 0.508)
			(layers "F.Cu" "F.Mask" "F.Paste")
			(net "P3E_CPU0_PE2_SS_RXP<7>")
		)
		(pad "199" smd rect
			(at 0 82.409792 270)
			(size 1.1938 0.508)
			(layers "F.Cu" "F.Mask" "F.Paste")
			(net "FM_PRSNT_2_6_N")
		)
		(pad "200" smd rect
			(at 3.4036 82.409792 270)
			(size 1.1938 0.508)
			(layers "F.Cu" "F.Mask" "F.Paste")
			(net "GND")
		)
		(pad "MH1" thru_hole circle
			(at 1.7018 -3.845052 270)
			(size 1.4224 1.4224)
			(drill 1.0414)
			(layers "*.Cu" "*.Mask")
			(remove_unused_layers no)
			(net "GND")
			(clearance 0.127)
			(thermal_gap 0.127)
		)
		(pad "MH2" thru_hole circle
			(at 1.7018 86.254844 270)
			(size 1.4224 1.4224)
			(drill 1.0414)
			(layers "*.Cu" "*.Mask")
			(remove_unused_layers no)
			(net "GND")
			(clearance 0.127)
			(thermal_gap 0.127)
		)
	)
)
